(kicad_pcb
	(version 20260206)
	(generator "pcbnew")
	(generator_version "10.0")
	(general
		(thickness 1.6)
		(legacy_teardrops no)
	)
	(paper "A4")
	(title_block
		(title "peb — Lightning_PEB_BRD.brd")
		(comment 1 "Lightning (Wiwynn / Facebook NVMe JBOF) / footprints 1610-1617 of 2563")
	)
	(layers
		(0 "F.Cu" signal "TOP")
		(4 "In1.Cu" signal "L2GND")
		(6 "In2.Cu" signal "L3")
		(8 "In3.Cu" signal "L4VCC")
		(10 "In4.Cu" signal "L5VCC")
		(12 "In5.Cu" signal "L6")
		(14 "In6.Cu" signal "L7GND")
		(2 "B.Cu" signal "BOTTOM")
		(9 "F.Adhes" user "F.Adhesive")
		(11 "B.Adhes" user "B.Adhesive")
		(13 "F.Paste" user "Package Geometry/Pastemask Top")
		(15 "B.Paste" user "Package Geometry/Pastemask Bottom")
		(5 "F.SilkS" user "Ref Des/Silkscreen Top")
		(7 "B.SilkS" user "Ref Des/Silkscreen Bottom")
		(1 "F.Mask" user "Board Geometry/Soldermask Top")
		(3 "B.Mask" user "Board Geometry/Soldermask Bottom")
		(17 "Dwgs.User" user "User.Drawings")
		(19 "Cmts.User" user "User.Comments")
		(21 "Eco1.User" user "User.Eco1")
		(23 "Eco2.User" user "User.Eco2")
		(25 "Edge.Cuts" user "Board Geometry/Outline")
		(27 "Margin" user)
		(31 "F.CrtYd" user "Package Geometry/Place Bound Top")
		(29 "B.CrtYd" user "Package Geometry/Place Bound Bottom")
		(35 "F.Fab" user "Ref Des/Assembly Top")
		(33 "B.Fab" user "Ref Des/Assembly Bottom")
	)
	(footprint ""
		(layer "F.Cu")
		(at 318.77 -54.483)
		(property "Reference" "PTC7"
			(at 0 0 0)
			(layer "F.SilkS")
			(hide yes)
			(effects
				(font
					(size 1.27 1.27)
				)
			)
		)
		(property "Value" "SE470UF2VDM-GP"
			(at 0 -9.6012 0)
			(unlocked yes)
			(layer "F.Fab")
			(hide yes)
			(effects
				(font
					(size 1.016 1.016)
					(thickness 0.1524)
				)
			)
		)
		(property "Device Type" "CT7343H83"
			(at 0 -11.1252 0)
			(unlocked yes)
			(layer "F.Fab")
			(hide yes)
			(effects
				(font
					(size 1.016 1.016)
					(thickness 0.1524)
				)
			)
		)
		(duplicate_pad_numbers_are_jumpers no)
		(fp_line
			(start -2.286 -4.8768)
			(end -2.286 -2.032)
			(stroke
				(width 0.1524)
				(type default)
			)
			(layer "F.SilkS")
		)
		(fp_line
			(start -2.286 4.8768)
			(end -2.286 2.032)
			(stroke
				(width 0.1524)
				(type default)
			)
			(layer "F.SilkS")
		)
		(fp_line
			(start 2.1082 -4.699)
			(end -2.1082 -4.699)
			(stroke
				(width 0.508)
				(type default)
			)
			(layer "F.SilkS")
		)
		(fp_line
			(start 2.286 -4.8768)
			(end -2.286 -4.8768)
			(stroke
				(width 0.1524)
				(type default)
			)
			(layer "F.SilkS")
		)
		(fp_line
			(start 2.286 -2.032)
			(end 2.286 -4.8768)
			(stroke
				(width 0.1524)
				(type default)
			)
			(layer "F.SilkS")
		)
		(fp_line
			(start 2.286 2.032)
			(end 2.286 4.8768)
			(stroke
				(width 0.1524)
				(type default)
			)
			(layer "F.SilkS")
		)
		(fp_line
			(start 2.286 4.8768)
			(end -2.286 4.8768)
			(stroke
				(width 0.1524)
				(type default)
			)
			(layer "F.SilkS")
		)
		(fp_rect
			(start -2.1463 3.6449)
			(end 2.1463 -3.6449)
			(stroke
				(width 0)
				(type default)
			)
			(fill no)
			(layer "F.CrtYd")
		)
		(fp_poly
			(pts
				(xy -2.54 4.953) (xy -2.54 4.2926) (xy -3.81 4.2926) (xy -3.81 -4.2926) (xy -2.54 -4.2926) (xy -2.54 -4.953)
				(xy 2.54 -4.953) (xy 2.54 -4.2926) (xy 3.81 -4.2926) (xy 3.81 -1.6256) (xy 2.1463 -1.6256) (xy 2.1463 -3.6449)
				(xy -2.1463 -3.6449) (xy -2.1463 3.6449) (xy 2.1463 3.6449) (xy 2.1463 -1.6129) (xy 3.81 -1.6129)
				(xy 3.81 4.2926) (xy 2.54 4.2926) (xy 2.54 4.953)
			)
			(stroke
				(width 0)
				(type default)
			)
			(fill no)
			(layer "F.CrtYd")
		)
		(fp_rect
			(start -3.81 4.2926)
			(end -2.54 -4.2926)
			(stroke
				(width 0)
				(type default)
			)
			(fill no)
			(layer "F.Fab")
		)
		(fp_rect
			(start -2.54 4.953)
			(end 2.54 -4.953)
			(stroke
				(width 0)
				(type default)
			)
			(fill no)
			(layer "F.Fab")
		)
		(fp_rect
			(start 2.54 4.2926)
			(end 3.81 -4.2926)
			(stroke
				(width 0)
				(type default)
			)
			(fill no)
			(layer "F.Fab")
		)
		(pad "1" smd rect
			(at 0 -3.1496)
			(size 2.413 2.286)
			(layers "F.Cu" "F.Mask" "F.Paste")
			(net "P0V9_E")
		)
		(pad "2" smd rect
			(at 0 3.1496)
			(size 2.413 2.286)
			(layers "F.Cu" "F.Mask" "F.Paste")
			(net "GND")
		)
		(zone
			(layer "F.Cu")
			(hatch none 0.5)
			(connect_pads
				(clearance 0)
			)
			(min_thickness 0.25)
			(keepout
				(tracks allowed)
				(vias not_allowed)
				(pads allowed)
				(copperpour not_allowed)
				(footprints allowed)
			)
			(placement
				(enabled no)
				(sheetname "")
			)
			(fill
				(thermal_gap 0.5)
				(thermal_bridge_width 0.5)
				(island_removal_mode 0)
			)
			(polygon
				(pts
					(xy 317.2587 -49.8856) (xy 320.2813 -49.8856) (xy 320.2813 -52.7812) (xy 320.2813 -53.1114) (xy 317.2587 -53.1114)
					(xy 317.2587 -52.7812)
				)
			)
		)
		(zone
			(layer "F.Cu")
			(hatch none 0.5)
			(connect_pads
				(clearance 0)
			)
			(min_thickness 0.25)
			(keepout
				(tracks allowed)
				(vias not_allowed)
				(pads allowed)
				(copperpour not_allowed)
				(footprints allowed)
			)
			(placement
				(enabled no)
				(sheetname "")
			)
			(fill
				(thermal_gap 0.5)
				(thermal_bridge_width 0.5)
				(island_removal_mode 0)
			)
			(polygon
				(pts
					(xy 320.2813 -56.1721) (xy 320.2813 -59.0804) (xy 317.2587 -59.0804) (xy 317.2587 -56.1848) (xy 317.2587 -55.8546)
					(xy 320.2813 -55.8546)
				)
			)
		)
	)
	(footprint ""
		(layer "F.Cu")
		(at 88.9 -41.275)
		(property "Reference" "PG8"
			(at 0 0 0)
			(layer "F.SilkS")
			(hide yes)
			(effects
				(font
					(size 1.27 1.27)
				)
			)
		)
		(property "Value" "GAP-CLOSE-PWR-3-GP"
			(at 0.0254 -6.5786 0)
			(unlocked yes)
			(layer "F.Fab")
			(hide yes)
			(effects
				(font
					(size 1.016 1.016)
					(thickness 0.1524)
				)
			)
		)
		(property "Device Type" "GAP-CLOSE-PWR-3"
			(at 0.0254 -8.255 0)
			(unlocked yes)
			(layer "F.Fab")
			(hide yes)
			(effects
				(font
					(size 1.016 1.016)
					(thickness 0.1524)
				)
			)
		)
		(duplicate_pad_numbers_are_jumpers no)
		(fp_rect
			(start -0.7112 0.4572)
			(end 0.7112 -0.4572)
			(stroke
				(width 0)
				(type default)
			)
			(fill no)
			(layer "F.CrtYd")
		)
		(fp_poly
			(pts
				(xy -0.7112 -0.4572) (xy 0.7112 -0.4572) (xy 0.7112 0.4572) (xy -0.7112 0.4572)
			)
			(stroke
				(width 0)
				(type default)
			)
			(fill no)
			(layer "F.Fab")
		)
		(pad "1" smd rect
			(at -0.3048 0)
			(size 0.6604 0.762)
			(layers "F.Cu" "F.Mask" "F.Paste")
			(net "P3V3_PWR")
		)
		(pad "2" smd rect
			(at 0.3048 0)
			(size 0.6604 0.762)
			(layers "F.Cu" "F.Mask" "F.Paste")
			(net "P3V3_STBY")
		)
	)
	(footprint ""
		(layer "F.Cu")
		(at 21.1582 -67.7672 -90)
		(property "Reference" "TP149"
			(at 0 0 270)
			(layer "F.SilkS")
			(hide yes)
			(effects
				(font
					(size 1.27 1.27)
				)
			)
		)
		(property "Value" "TPAD28-2-GP"
			(at -0.0127 -1.6637 270)
			(unlocked yes)
			(layer "F.Fab")
			(hide yes)
			(effects
				(font
					(size 1.016 1.016)
					(thickness 0.1524)
				)
			)
		)
		(property "Device Type" "TPAD28"
			(at -0.0127 -3.1877 270)
			(unlocked yes)
			(layer "F.Fab")
			(hide yes)
			(effects
				(font
					(size 1.016 1.016)
					(thickness 0.1524)
				)
			)
		)
		(duplicate_pad_numbers_are_jumpers no)
		(fp_poly
			(pts
				(arc
					(start 0 -0.3556)
					(mid 0 0.3556)
					(end 0 -0.3556)
				)
			)
			(stroke
				(width 0)
				(type default)
			)
			(fill no)
			(layer "F.CrtYd")
		)
		(fp_poly
			(pts
				(arc
					(start 0 -0.6096)
					(mid 0 0.6096)
					(end 0 -0.6096)
				)
			)
			(stroke
				(width 0)
				(type default)
			)
			(fill no)
			(layer "F.Fab")
		)
		(pad "1" smd circle
			(at 0 0 270)
			(size 0.7112 0.7112)
			(layers "F.Cu" "F.Mask" "F.Paste")
			(net "TP_SDP2")
		)
	)
	(footprint ""
		(layer "F.Cu")
		(at 224.536 -23.241 180)
		(property "Reference" "R3721"
			(at 0 0 180)
			(layer "F.SilkS")
			(hide yes)
			(effects
				(font
					(size 1.27 1.27)
				)
			)
		)
		(property "Value" "4K7R2F-GP"
			(at 0.064008 -3.993896 180)
			(unlocked yes)
			(layer "F.Fab")
			(hide yes)
			(effects
				(font
					(size 1.016 1.016)
					(thickness 0.1524)
				)
			)
		)
		(property "Device Type" "R402H16"
			(at 0.064008 -5.517896 180)
			(unlocked yes)
			(layer "F.Fab")
			(hide yes)
			(effects
				(font
					(size 1.016 1.016)
					(thickness 0.1524)
				)
			)
		)
		(duplicate_pad_numbers_are_jumpers no)
		(fp_line
			(start 0.508 -0.9398)
			(end -0.508 -0.9398)
			(stroke
				(width 0.1524)
				(type default)
			)
			(layer "F.SilkS")
		)
		(fp_line
			(start -0.508 -0.9398)
			(end -0.508 0.9398)
			(stroke
				(width 0.1524)
				(type default)
			)
			(layer "F.SilkS")
		)
		(fp_rect
			(start -0.508 0.9398)
			(end 0.508 -0.9398)
			(stroke
				(width 0)
				(type default)
			)
			(fill no)
			(layer "F.CrtYd")
		)
		(fp_rect
			(start -0.508 0.9398)
			(end 0.508 -0.9398)
			(stroke
				(width 0)
				(type default)
			)
			(fill no)
			(layer "F.Fab")
		)
		(pad "1" smd custom
			(at 0 -0.4445 180)
			(size 0.1397 0.1397)
			(layers "F.Cu" "F.Mask" "F.Paste")
			(net "HOST6_RST_N_LS")
			(options
				(clearance outline)
				(anchor circle)
			)
			(primitives
				(gr_poly
					(pts
						(arc
							(start -0.1778 -0.2794)
							(mid -0.249642 -0.249642)
							(end -0.2794 -0.1778)
						)
						(arc
							(start -0.2794 0.1778)
							(mid -0.249642 0.249642)
							(end -0.1778 0.2794)
						)
						(arc
							(start 0.1778 0.2794)
							(mid 0.249642 0.249642)
							(end 0.2794 0.1778)
						)
						(arc
							(start 0.2794 -0.1778)
							(mid 0.249642 -0.249642)
							(end 0.1778 -0.2794)
						)
					)
					(width 0)
					(fill yes)
				)
			)
		)
		(pad "2" smd custom
			(at 0 0.4445 180)
			(size 0.1397 0.1397)
			(layers "F.Cu" "F.Mask" "F.Paste")
			(net "GND")
			(options
				(clearance outline)
				(anchor circle)
			)
			(primitives
				(gr_poly
					(pts
						(arc
							(start -0.1778 -0.2794)
							(mid -0.249642 -0.249642)
							(end -0.2794 -0.1778)
						)
						(arc
							(start -0.2794 0.1778)
							(mid -0.249642 0.249642)
							(end -0.1778 0.2794)
						)
						(arc
							(start 0.1778 0.2794)
							(mid 0.249642 0.249642)
							(end 0.2794 0.1778)
						)
						(arc
							(start 0.2794 -0.1778)
							(mid 0.249642 -0.249642)
							(end 0.1778 -0.2794)
						)
					)
					(width 0)
					(fill yes)
				)
			)
		)
	)
	(footprint ""
		(layer "F.Cu")
		(at 160.528 -85.2424)
		(property "Reference" "R77"
			(at 0 0 0)
			(layer "F.SilkS")
			(hide yes)
			(effects
				(font
					(size 1.27 1.27)
				)
			)
		)
		(property "Value" "0R2J-2-GP"
			(at 0.064008 -3.993896 0)
			(unlocked yes)
			(layer "F.Fab")
			(hide yes)
			(effects
				(font
					(size 1.016 1.016)
					(thickness 0.1524)
				)
			)
		)
		(property "Device Type" "R402H16"
			(at 0.064008 -5.517896 0)
			(unlocked yes)
			(layer "F.Fab")
			(hide yes)
			(effects
				(font
					(size 1.016 1.016)
					(thickness 0.1524)
				)
			)
		)
		(duplicate_pad_numbers_are_jumpers no)
		(fp_line
			(start -0.508 -0.9398)
			(end -0.508 0.9398)
			(stroke
				(width 0.1524)
				(type default)
			)
			(layer "F.SilkS")
		)
		(fp_line
			(start 0.508 -0.9398)
			(end -0.508 -0.9398)
			(stroke
				(width 0.1524)
				(type default)
			)
			(layer "F.SilkS")
		)
		(fp_rect
			(start -0.508 0.9398)
			(end 0.508 -0.9398)
			(stroke
				(width 0)
				(type default)
			)
			(fill no)
			(layer "F.CrtYd")
		)
		(fp_rect
			(start -0.508 0.9398)
			(end 0.508 -0.9398)
			(stroke
				(width 0)
				(type default)
			)
			(fill no)
			(layer "F.Fab")
		)
		(pad "1" smd custom
			(at 0 -0.4445)
			(size 0.1397 0.1397)
			(layers "F.Cu" "F.Mask" "F.Paste")
			(net "PCIE_CLKGEN2_OE0_R")
			(options
				(clearance outline)
				(anchor circle)
			)
			(primitives
				(gr_poly
					(pts
						(arc
							(start -0.1778 -0.2794)
							(mid -0.249642 -0.249642)
							(end -0.2794 -0.1778)
						)
						(arc
							(start -0.2794 0.1778)
							(mid -0.249642 0.249642)
							(end -0.1778 0.2794)
						)
						(arc
							(start 0.1778 0.2794)
							(mid 0.249642 0.249642)
							(end 0.2794 0.1778)
						)
						(arc
							(start 0.2794 -0.1778)
							(mid 0.249642 -0.249642)
							(end 0.1778 -0.2794)
						)
					)
					(width 0)
					(fill yes)
				)
			)
		)
		(pad "2" smd custom
			(at 0 0.4445)
			(size 0.1397 0.1397)
			(layers "F.Cu" "F.Mask" "F.Paste")
			(net "PCIE_CLKGEN2_OE0")
			(options
				(clearance outline)
				(anchor circle)
			)
			(primitives
				(gr_poly
					(pts
						(arc
							(start -0.1778 -0.2794)
							(mid -0.249642 -0.249642)
							(end -0.2794 -0.1778)
						)
						(arc
							(start -0.2794 0.1778)
							(mid -0.249642 0.249642)
							(end -0.1778 0.2794)
						)
						(arc
							(start 0.1778 0.2794)
							(mid 0.249642 0.249642)
							(end 0.2794 0.1778)
						)
						(arc
							(start 0.2794 -0.1778)
							(mid 0.249642 -0.249642)
							(end 0.1778 -0.2794)
						)
					)
					(width 0)
					(fill yes)
				)
			)
		)
	)
	(footprint ""
		(layer "F.Cu")
		(at 212.6234 -26.8224 -90)
		(property "Reference" "R749"
			(at 0 0 270)
			(layer "F.SilkS")
			(hide yes)
			(effects
				(font
					(size 1.27 1.27)
				)
			)
		)
		(property "Value" "0R2J-2-GP"
			(at 0.064008 -3.993896 270)
			(unlocked yes)
			(layer "F.Fab")
			(hide yes)
			(effects
				(font
					(size 1.016 1.016)
					(thickness 0.1524)
				)
			)
		)
		(property "Device Type" "R402H16"
			(at 0.064008 -5.517896 270)
			(unlocked yes)
			(layer "F.Fab")
			(hide yes)
			(effects
				(font
					(size 1.016 1.016)
					(thickness 0.1524)
				)
			)
		)
		(duplicate_pad_numbers_are_jumpers no)
		(fp_line
			(start -0.508 -0.9398)
			(end -0.508 0.9398)
			(stroke
				(width 0.1524)
				(type default)
			)
			(layer "F.SilkS")
		)
		(fp_line
			(start 0.508 -0.9398)
			(end -0.508 -0.9398)
			(stroke
				(width 0.1524)
				(type default)
			)
			(layer "F.SilkS")
		)
		(fp_rect
			(start -0.508 0.9398)
			(end 0.508 -0.9398)
			(stroke
				(width 0)
				(type default)
			)
			(fill no)
			(layer "F.CrtYd")
		)
		(fp_rect
			(start -0.508 0.9398)
			(end 0.508 -0.9398)
			(stroke
				(width 0)
				(type default)
			)
			(fill no)
			(layer "F.Fab")
		)
		(pad "1" smd custom
			(at 0 -0.4445 270)
			(size 0.1397 0.1397)
			(layers "F.Cu" "F.Mask" "F.Paste")
			(net "DUT_TAP_SEL_R")
			(options
				(clearance outline)
				(anchor circle)
			)
			(primitives
				(gr_poly
					(pts
						(arc
							(start -0.1778 -0.2794)
							(mid -0.249642 -0.249642)
							(end -0.2794 -0.1778)
						)
						(arc
							(start -0.2794 0.1778)
							(mid -0.249642 0.249642)
							(end -0.1778 0.2794)
						)
						(arc
							(start 0.1778 0.2794)
							(mid 0.249642 0.249642)
							(end 0.2794 0.1778)
						)
						(arc
							(start 0.2794 -0.1778)
							(mid 0.249642 -0.249642)
							(end 0.1778 -0.2794)
						)
					)
					(width 0)
					(fill yes)
				)
			)
		)
		(pad "2" smd custom
			(at 0 0.4445 270)
			(size 0.1397 0.1397)
			(layers "F.Cu" "F.Mask" "F.Paste")
			(net "DUT_TAP_SEL")
			(options
				(clearance outline)
				(anchor circle)
			)
			(primitives
				(gr_poly
					(pts
						(arc
							(start -0.1778 -0.2794)
							(mid -0.249642 -0.249642)
							(end -0.2794 -0.1778)
						)
						(arc
							(start -0.2794 0.1778)
							(mid -0.249642 0.249642)
							(end -0.1778 0.2794)
						)
						(arc
							(start 0.1778 0.2794)
							(mid 0.249642 0.249642)
							(end 0.2794 0.1778)
						)
						(arc
							(start 0.2794 -0.1778)
							(mid 0.249642 -0.249642)
							(end 0.1778 -0.2794)
						)
					)
					(width 0)
					(fill yes)
				)
			)
		)
	)
	(footprint ""
		(layer "F.Cu")
		(at 16.889476 -141.456664)
		(property "Reference" "TP181"
			(at 0 0 0)
			(layer "F.SilkS")
			(hide yes)
			(effects
				(font
					(size 1.27 1.27)
				)
			)
		)
		(property "Value" "TPAD28-2-GP"
			(at -0.0127 -1.6637 0)
			(unlocked yes)
			(layer "F.Fab")
			(hide yes)
			(effects
				(font
					(size 1.016 1.016)
					(thickness 0.1524)
				)
			)
		)
		(property "Device Type" "TPAD28"
			(at -0.0127 -3.1877 0)
			(unlocked yes)
			(layer "F.Fab")
			(hide yes)
			(effects
				(font
					(size 1.016 1.016)
					(thickness 0.1524)
				)
			)
		)
		(duplicate_pad_numbers_are_jumpers no)
		(fp_poly
			(pts
				(arc
					(start 0.3556 0)
					(mid -0.3556 0)
					(end 0.3556 0)
				)
			)
			(stroke
				(width 0)
				(type default)
			)
			(fill no)
			(layer "F.CrtYd")
		)
		(fp_poly
			(pts
				(arc
					(start 0.6096 0)
					(mid -0.6096 0)
					(end 0.6096 0)
				)
			)
			(stroke
				(width 0)
				(type default)
			)
			(fill no)
			(layer "F.Fab")
		)
		(pad "1" smd circle
			(at 0 0)
			(size 0.7112 0.7112)
			(layers "F.Cu" "F.Mask" "F.Paste")
			(net "FM_BMC_RESET_N")
		)
	)
	(footprint ""
		(layer "F.Cu")
		(at 41.739058 -113.721134 90)
		(property "Reference" "R156"
			(at 0 0 90)
			(layer "F.SilkS")
			(hide yes)
			(effects
				(font
					(size 1.27 1.27)
				)
			)
		)
		(property "Value" "4K7R2F-GP"
			(at 0.064008 -3.993896 90)
			(unlocked yes)
			(layer "F.Fab")
			(hide yes)
			(effects
				(font
					(size 1.016 1.016)
					(thickness 0.1524)
				)
			)
		)
		(property "Device Type" "R402H16"
			(at 0.064008 -5.517896 90)
			(unlocked yes)
			(layer "F.Fab")
			(hide yes)
			(effects
				(font
					(size 1.016 1.016)
					(thickness 0.1524)
				)
			)
		)
		(duplicate_pad_numbers_are_jumpers no)
		(fp_line
			(start 0.508 -0.9398)
			(end -0.508 -0.9398)
			(stroke
				(width 0.1524)
				(type default)
			)
			(layer "F.SilkS")
		)
		(fp_line
			(start -0.508 -0.9398)
			(end -0.508 0.9398)
			(stroke
				(width 0.1524)
				(type default)
			)
			(layer "F.SilkS")
		)
		(fp_rect
			(start -0.508 0.9398)
			(end 0.508 -0.9398)
			(stroke
				(width 0)
				(type default)
			)
			(fill no)
			(layer "F.CrtYd")
		)
		(fp_rect
			(start -0.508 0.9398)
			(end 0.508 -0.9398)
			(stroke
				(width 0)
				(type default)
			)
			(fill no)
			(layer "F.Fab")
		)
		(pad "1" smd custom
			(at 0 -0.4445 90)
			(size 0.1397 0.1397)
			(layers "F.Cu" "F.Mask" "F.Paste")
			(net "BMC_ID_LED")
			(options
				(clearance outline)
				(anchor circle)
			)
			(primitives
				(gr_poly
					(pts
						(arc
							(start -0.1778 -0.2794)
							(mid -0.249642 -0.249642)
							(end -0.2794 -0.1778)
						)
						(arc
							(start -0.2794 0.1778)
							(mid -0.249642 0.249642)
							(end -0.1778 0.2794)
						)
						(arc
							(start 0.1778 0.2794)
							(mid 0.249642 0.249642)
							(end 0.2794 0.1778)
						)
						(arc
							(start 0.2794 -0.1778)
							(mid 0.249642 -0.249642)
							(end 0.1778 -0.2794)
						)
					)
					(width 0)
					(fill yes)
				)
			)
		)
		(pad "2" smd custom
			(at 0 0.4445 90)
			(size 0.1397 0.1397)
			(layers "F.Cu" "F.Mask" "F.Paste")
			(net "P3V3_STBY")
			(options
				(clearance outline)
				(anchor circle)
			)
			(primitives
				(gr_poly
					(pts
						(arc
							(start -0.1778 -0.2794)
							(mid -0.249642 -0.249642)
							(end -0.2794 -0.1778)
						)
						(arc
							(start -0.2794 0.1778)
							(mid -0.249642 0.249642)
							(end -0.1778 0.2794)
						)
						(arc
							(start 0.1778 0.2794)
							(mid 0.249642 0.249642)
							(end 0.2794 0.1778)
						)
						(arc
							(start 0.2794 -0.1778)
							(mid 0.249642 -0.249642)
							(end 0.1778 -0.2794)
						)
					)
					(width 0)
					(fill yes)
				)
			)
		)
	)
)
